(kicad_pcb
	(version 20260206)
	(generator "pcbnew")
	(generator_version "10.0")
	(general
		(thickness 1.6)
		(legacy_teardrops no)
	)
	(paper "A4")
	(title_block
		(title "Wiwynn_Tioga_Pass_MB.brd")
		(comment 1 "Tioga Pass / footprint 2254 of 4770 (U5D1), pads 2188-2295 of 3647")
	)
	(layers
		(0 "F.Cu" signal "TOP")
		(4 "In1.Cu" signal "L2GND")
		(6 "In2.Cu" signal "L3")
		(8 "In3.Cu" signal "L4GND")
		(10 "In4.Cu" signal "L5")
		(12 "In5.Cu" signal "L6GND")
		(14 "In6.Cu" signal "L7VCC")
		(16 "In7.Cu" signal "L8VCC")
		(18 "In8.Cu" signal "L9GND")
		(20 "In9.Cu" signal "L10")
		(22 "In10.Cu" signal "L11GND")
		(24 "In11.Cu" signal "L12")
		(26 "In12.Cu" signal "L13GND")
		(2 "B.Cu" signal "BOTTOM")
		(9 "F.Adhes" user "F.Adhesive")
		(11 "B.Adhes" user "B.Adhesive")
		(13 "F.Paste" user "Package Geometry/Pastemask Top")
		(15 "B.Paste" user "Package Geometry/Pastemask Bottom")
		(5 "F.SilkS" user "Ref Des/Silkscreen Top")
		(7 "B.SilkS" user "Ref Des/Silkscreen Bottom")
		(1 "F.Mask" user "Board Geometry/Soldermask Top")
		(3 "B.Mask" user "Board Geometry/Soldermask Bottom")
		(17 "Dwgs.User" user "User.Drawings")
		(19 "Cmts.User" user "User.Comments")
		(21 "Eco1.User" user "User.Eco1")
		(23 "Eco2.User" user "User.Eco2")
		(25 "Edge.Cuts" user "Board Geometry/Outline")
		(27 "Margin" user)
		(31 "F.CrtYd" user "Package Geometry/Place Bound Top")
		(29 "B.CrtYd" user "Package Geometry/Place Bound Bottom")
		(35 "F.Fab" user "Ref Des/Assembly Top")
		(33 "B.Fab" user "Ref Des/Assembly Bottom")
	)
	(footprint ""
		(layer "F.Cu")
		(at 270.000222 -76.550012 180)
		(property "Reference" "U5D1"
			(at 19.124422 31.601918 0)
			(unlocked yes)
			(layer "F.SilkS")
			(effects
				(font
					(size 0.7874 0.5842)
					(thickness 0.1524)
				)
			)
		)
		(property "Value" ""
			(at 0 0 180)
			(layer "F.Fab")
			(effects
				(font
					(size 1.27 1.27)
				)
			)
		)
		(duplicate_pad_numbers_are_jumpers no)
		(pad "DF77" smd circle
			(at 29.523944 15.197074)
			(size 0.4318 0.4318)
			(layers "F.Cu" "F.Mask" "F.Paste")
			(net "M_F_DQ<14>")
		)
		(pad "DF79" smd circle
			(at 31.240984 15.197074)
			(size 0.4318 0.4318)
			(layers "F.Cu" "F.Mask" "F.Paste")
			(net "GND")
		)
		(pad "DF81" smd circle
			(at 32.958024 15.197074)
			(size 0.4318 0.4318)
			(layers "F.Cu" "F.Mask" "F.Paste")
			(net "M_E_DQ<11>")
		)
		(pad "DF83" smd circle
			(at 34.675064 15.197074)
			(size 0.4318 0.4318)
			(layers "F.Cu" "F.Mask" "F.Paste")
			(net "GND")
		)
		(pad "DF85" smd custom
			(at 36.392104 15.197074 270)
			(size 0.10795 0.10795)
			(layers "F.Cu" "F.Mask" "F.Paste")
			(net "GND")
			(options
				(clearance outline)
				(anchor circle)
			)
			(primitives
				(gr_poly
					(pts
						(arc
							(start 0.2159 -0.0381)
							(mid 0 -0.254)
							(end -0.2159 -0.0381)
						)
						(arc
							(start -0.2159 0.0381)
							(mid 0 0.254)
							(end 0.2159 0.0381)
						)
					)
					(width 0)
					(fill yes)
				)
			)
		)
		(pad "DG2" smd custom
			(at -36.392104 17.492726 90)
			(size 0.10795 0.10795)
			(layers "F.Cu" "F.Mask" "F.Paste")
			(net "GND")
			(options
				(clearance outline)
				(anchor circle)
			)
			(primitives
				(gr_poly
					(pts
						(arc
							(start 0.2159 -0.0381)
							(mid 0 -0.254)
							(end -0.2159 -0.0381)
						)
						(arc
							(start -0.2159 0.0381)
							(mid 0 0.254)
							(end 0.2159 0.0381)
						)
					)
					(width 0)
					(fill yes)
				)
			)
		)
		(pad "DG4" smd circle
			(at -34.675064 17.492726)
			(size 0.4318 0.4318)
			(layers "F.Cu" "F.Mask" "F.Paste")
			(net "P3E_CPU0_PE1_SS_TXN<4>")
		)
		(pad "DG6" smd circle
			(at -32.958024 17.492726)
			(size 0.4318 0.4318)
			(layers "F.Cu" "F.Mask" "F.Paste")
			(net "P3E_CPU0_PE3_OCP_TXP<12>")
		)
		(pad "DG8" smd circle
			(at -31.240984 17.492726)
			(size 0.4318 0.4318)
			(layers "F.Cu" "F.Mask" "F.Paste")
			(net "PVCCIO_CPU0")
		)
		(pad "DG10" smd circle
			(at -29.523944 17.492726)
			(size 0.4318 0.4318)
			(layers "F.Cu" "F.Mask" "F.Paste")
			(net "P3E_CPU0_PE3_OCP_RXN<11>")
		)
		(pad "DG12" smd circle
			(at -27.806904 17.492726)
			(size 0.4318 0.4318)
			(layers "F.Cu" "F.Mask" "F.Paste")
			(net "P3E_CPU0_PE3_OCP_RXN<10>")
		)
		(pad "DG14" smd circle
			(at -26.090118 17.492726)
			(size 0.4318 0.4318)
			(layers "F.Cu" "F.Mask" "F.Paste")
			(net "GND")
		)
		(pad "DG16" smd circle
			(at -24.373078 17.492726)
			(size 0.4318 0.4318)
			(layers "F.Cu" "F.Mask" "F.Paste")
			(net "GND")
		)
		(pad "DG18" smd circle
			(at -22.656038 17.492726)
			(size 0.4318 0.4318)
			(layers "F.Cu" "F.Mask" "F.Paste")
			(net "TP_CPU0_UPI2_RSVD_CM13")
		)
		(pad "DG20" smd circle
			(at -20.938998 17.492726)
			(size 0.4318 0.4318)
			(layers "F.Cu" "F.Mask" "F.Paste")
			(net "TP_CPU0_UPI2_RSVD_CH11")
		)
		(pad "DG22" smd circle
			(at -19.221958 17.492726)
			(size 0.4318 0.4318)
			(layers "F.Cu" "F.Mask" "F.Paste")
			(net "GND")
		)
		(pad "DG24" smd circle
			(at -17.504918 17.492726)
			(size 0.4318 0.4318)
			(layers "F.Cu" "F.Mask" "F.Paste")
			(net "GND")
		)
		(pad "DG26" smd circle
			(at -15.787878 17.492726)
			(size 0.4318 0.4318)
			(layers "F.Cu" "F.Mask" "F.Paste")
			(net "M_E_DQS_DN<16>")
		)
		(pad "DG28" smd circle
			(at -14.071092 17.492726)
			(size 0.4318 0.4318)
			(layers "F.Cu" "F.Mask" "F.Paste")
			(net "M_E_DQ<60>")
		)
		(pad "DG30" smd circle
			(at -12.354052 17.492726)
			(size 0.4318 0.4318)
			(layers "F.Cu" "F.Mask" "F.Paste")
			(net "M_F_DQ<42>")
		)
		(pad "DG32" smd circle
			(at -10.637012 17.492726)
			(size 0.4318 0.4318)
			(layers "F.Cu" "F.Mask" "F.Paste")
			(net "M_F_DQS_DN<14>")
		)
		(pad "DG34" smd circle
			(at -8.919972 17.492726)
			(size 0.4318 0.4318)
			(layers "F.Cu" "F.Mask" "F.Paste")
			(net "M_F_DQ<44>")
		)
		(pad "DG36" smd circle
			(at -7.202932 17.492726)
			(size 0.4318 0.4318)
			(layers "F.Cu" "F.Mask" "F.Paste")
			(net "TP_CPU0_RSVD_44")
		)
		(pad "DG38" smd circle
			(at -5.485892 17.492726)
			(size 0.4318 0.4318)
			(layers "F.Cu" "F.Mask" "F.Paste")
			(net "M_F_DQ<35>")
		)
		(pad "DG40" smd circle
			(at -3.769106 17.492726)
			(size 0.4318 0.4318)
			(layers "F.Cu" "F.Mask" "F.Paste")
			(net "M_F_DQS_DN<4>")
		)
		(pad "DG42" smd circle
			(at -2.052066 17.492726)
			(size 0.4318 0.4318)
			(layers "F.Cu" "F.Mask" "F.Paste")
			(net "M_F_DQ<33>")
		)
		(pad "DG44" smd circle
			(at 1.193546 15.692628)
			(size 0.508 0.508)
			(layers "F.Cu" "F.Mask" "F.Paste")
			(net "SVID_CLK1_CPU0")
		)
		(pad "DG46" smd circle
			(at 2.910586 15.692628)
			(size 0.4318 0.4318)
			(layers "F.Cu" "F.Mask" "F.Paste")
			(net "M_F_CS_N<3>")
		)
		(pad "DG48" smd circle
			(at 4.627626 15.692628)
			(size 0.4318 0.4318)
			(layers "F.Cu" "F.Mask" "F.Paste")
			(net "M_F_ODT<1>")
		)
		(pad "DG50" smd circle
			(at 6.344412 15.692628)
			(size 0.4318 0.4318)
			(layers "F.Cu" "F.Mask" "F.Paste")
			(net "M_F_ODT<0>")
		)
		(pad "DG52" smd circle
			(at 8.061452 15.692628)
			(size 0.4318 0.4318)
			(layers "F.Cu" "F.Mask" "F.Paste")
			(net "M_F_MA<16>")
		)
		(pad "DG54" smd circle
			(at 9.778492 15.692628)
			(size 0.4318 0.4318)
			(layers "F.Cu" "F.Mask" "F.Paste")
			(net "M_F_CLK_DP<1>")
		)
		(pad "DG56" smd circle
			(at 11.495532 15.692628)
			(size 0.4318 0.4318)
			(layers "F.Cu" "F.Mask" "F.Paste")
			(net "M_F_CLK_DP<3>")
		)
		(pad "DG58" smd circle
			(at 13.212572 15.692628)
			(size 0.4318 0.4318)
			(layers "F.Cu" "F.Mask" "F.Paste")
			(net "M_F_MA<3>")
		)
		(pad "DG60" smd circle
			(at 14.929612 15.692628)
			(size 0.4318 0.4318)
			(layers "F.Cu" "F.Mask" "F.Paste")
			(net "M_F_MA<12>")
		)
		(pad "DG62" smd circle
			(at 16.646398 15.692628)
			(size 0.4318 0.4318)
			(layers "F.Cu" "F.Mask" "F.Paste")
			(net "M_F_CKE<0>")
		)
		(pad "DG64" smd circle
			(at 18.363438 15.692628)
			(size 0.4318 0.4318)
			(layers "F.Cu" "F.Mask" "F.Paste")
			(net "TP_CPU0_RSVD_43")
		)
		(pad "DG66" smd circle
			(at 20.080478 15.692628)
			(size 0.4318 0.4318)
			(layers "F.Cu" "F.Mask" "F.Paste")
			(net "GND")
		)
		(pad "DG68" smd circle
			(at 21.797518 15.692628)
			(size 0.4318 0.4318)
			(layers "F.Cu" "F.Mask" "F.Paste")
			(net "GND")
		)
		(pad "DG70" smd circle
			(at 23.514558 15.692628)
			(size 0.4318 0.4318)
			(layers "F.Cu" "F.Mask" "F.Paste")
			(net "M_F_DQ<16>")
		)
		(pad "DG72" smd circle
			(at 25.231598 15.692628)
			(size 0.4318 0.4318)
			(layers "F.Cu" "F.Mask" "F.Paste")
			(net "M_F_DQ<21>")
		)
		(pad "DG74" smd circle
			(at 26.948384 15.692628)
			(size 0.4318 0.4318)
			(layers "F.Cu" "F.Mask" "F.Paste")
			(net "M_F_DQS_DP<10>")
		)
		(pad "DG76" smd circle
			(at 28.665424 15.692628)
			(size 0.4318 0.4318)
			(layers "F.Cu" "F.Mask" "F.Paste")
			(net "GND")
		)
		(pad "DG78" smd circle
			(at 30.382464 15.692628)
			(size 0.4318 0.4318)
			(layers "F.Cu" "F.Mask" "F.Paste")
			(net "GND")
		)
		(pad "DG80" smd circle
			(at 32.099504 15.692628)
			(size 0.4318 0.4318)
			(layers "F.Cu" "F.Mask" "F.Paste")
			(net "GND")
		)
		(pad "DG82" smd circle
			(at 33.816544 15.692628)
			(size 0.4318 0.4318)
			(layers "F.Cu" "F.Mask" "F.Paste")
			(net "GND")
		)
		(pad "DG84" smd circle
			(at 35.533584 15.692628)
			(size 0.4318 0.4318)
			(layers "F.Cu" "F.Mask" "F.Paste")
			(net "M_D_DQ<8>")
		)
		(pad "DH3" smd circle
			(at -35.533584 17.988026)
			(size 0.4318 0.4318)
			(layers "F.Cu" "F.Mask" "F.Paste")
			(net "P3E_CPU0_PE1_SS_TXP<5>")
		)
		(pad "DH5" smd circle
			(at -33.816544 17.988026)
			(size 0.4318 0.4318)
			(layers "F.Cu" "F.Mask" "F.Paste")
			(net "P3E_CPU0_PE3_OCP_TXP<11>")
		)
		(pad "DH7" smd circle
			(at -32.099504 17.988026)
			(size 0.4318 0.4318)
			(layers "F.Cu" "F.Mask" "F.Paste")
			(net "PVCCIO_CPU0")
		)
		(pad "DH9" smd circle
			(at -30.382464 17.988026)
			(size 0.4318 0.4318)
			(layers "F.Cu" "F.Mask" "F.Paste")
			(net "P3E_CPU0_PE1_SS_RXN<5>")
		)
		(pad "DH11" smd circle
			(at -28.665424 17.988026)
			(size 0.4318 0.4318)
			(layers "F.Cu" "F.Mask" "F.Paste")
			(net "P3E_CPU0_PE3_OCP_RXP<9>")
		)
		(pad "DH13" smd circle
			(at -26.948384 17.988026)
			(size 0.4318 0.4318)
			(layers "F.Cu" "F.Mask" "F.Paste")
			(net "GND")
		)
		(pad "DH15" smd circle
			(at -25.231598 17.988026)
			(size 0.4318 0.4318)
			(layers "F.Cu" "F.Mask" "F.Paste")
			(net "GND")
		)
		(pad "DH17" smd circle
			(at -23.514558 17.988026)
			(size 0.4318 0.4318)
			(layers "F.Cu" "F.Mask" "F.Paste")
			(net "TP_CPU0_UPI2_RSVD_CH13")
		)
		(pad "DH19" smd circle
			(at -21.797518 17.988026)
			(size 0.4318 0.4318)
			(layers "F.Cu" "F.Mask" "F.Paste")
			(net "TP_CPU0_UPI2_RSVD_CF13")
		)
		(pad "DH21" smd circle
			(at -20.080478 17.988026)
			(size 0.4318 0.4318)
			(layers "F.Cu" "F.Mask" "F.Paste")
			(net "GND")
		)
		(pad "DH23" smd circle
			(at -18.363438 17.988026)
			(size 0.4318 0.4318)
			(layers "F.Cu" "F.Mask" "F.Paste")
			(net "GND")
		)
		(pad "DH25" smd circle
			(at -16.646398 17.988026)
			(size 0.4318 0.4318)
			(layers "F.Cu" "F.Mask" "F.Paste")
			(net "GND")
		)
		(pad "DH27" smd circle
			(at -14.929612 17.988026)
			(size 0.4318 0.4318)
			(layers "F.Cu" "F.Mask" "F.Paste")
			(net "GND")
		)
		(pad "DH29" smd circle
			(at -13.212572 17.988026)
			(size 0.4318 0.4318)
			(layers "F.Cu" "F.Mask" "F.Paste")
			(net "GND")
		)
		(pad "DH31" smd circle
			(at -11.495532 17.988026)
			(size 0.4318 0.4318)
			(layers "F.Cu" "F.Mask" "F.Paste")
			(net "GND")
		)
		(pad "DH33" smd circle
			(at -9.778492 17.988026)
			(size 0.4318 0.4318)
			(layers "F.Cu" "F.Mask" "F.Paste")
			(net "GND")
		)
		(pad "DH35" smd circle
			(at -8.061452 17.988026)
			(size 0.4318 0.4318)
			(layers "F.Cu" "F.Mask" "F.Paste")
			(net "GND")
		)
		(pad "DH37" smd circle
			(at -6.344412 17.988026)
			(size 0.4318 0.4318)
			(layers "F.Cu" "F.Mask" "F.Paste")
			(net "GND")
		)
		(pad "DH39" smd circle
			(at -4.627626 17.988026)
			(size 0.4318 0.4318)
			(layers "F.Cu" "F.Mask" "F.Paste")
			(net "M_F_DQ<39>")
		)
		(pad "DH41" smd circle
			(at -2.910586 17.988026)
			(size 0.4318 0.4318)
			(layers "F.Cu" "F.Mask" "F.Paste")
			(net "GND")
		)
		(pad "DH45" smd circle
			(at 2.052066 16.187674)
			(size 0.4318 0.4318)
			(layers "F.Cu" "F.Mask" "F.Paste")
			(net "PVDDQ_DEF")
		)
		(pad "DH47" smd circle
			(at 3.769106 16.187674)
			(size 0.4318 0.4318)
			(layers "F.Cu" "F.Mask" "F.Paste")
			(net "PVDDQ_DEF")
		)
		(pad "DH49" smd circle
			(at 5.485892 16.187674)
			(size 0.4318 0.4318)
			(layers "F.Cu" "F.Mask" "F.Paste")
			(net "PVDDQ_DEF")
		)
		(pad "DH51" smd circle
			(at 7.202932 16.187674)
			(size 0.4318 0.4318)
			(layers "F.Cu" "F.Mask" "F.Paste")
			(net "PVDDQ_DEF")
		)
		(pad "DH53" smd circle
			(at 8.919972 16.187674)
			(size 0.4318 0.4318)
			(layers "F.Cu" "F.Mask" "F.Paste")
			(net "PVDDQ_DEF")
		)
		(pad "DH55" smd circle
			(at 10.637012 16.187674)
			(size 0.4318 0.4318)
			(layers "F.Cu" "F.Mask" "F.Paste")
			(net "PVDDQ_DEF")
		)
		(pad "DH57" smd circle
			(at 12.354052 16.187674)
			(size 0.4318 0.4318)
			(layers "F.Cu" "F.Mask" "F.Paste")
			(net "PVDDQ_DEF")
		)
		(pad "DH59" smd circle
			(at 14.071092 16.187674)
			(size 0.4318 0.4318)
			(layers "F.Cu" "F.Mask" "F.Paste")
			(net "PVDDQ_DEF")
		)
		(pad "DH61" smd circle
			(at 15.787878 16.187674)
			(size 0.4318 0.4318)
			(layers "F.Cu" "F.Mask" "F.Paste")
			(net "PVDDQ_DEF")
		)
		(pad "DH63" smd circle
			(at 17.504918 16.187674)
			(size 0.4318 0.4318)
			(layers "F.Cu" "F.Mask" "F.Paste")
			(net "PVDDQ_DEF")
		)
		(pad "DH65" smd circle
			(at 19.221958 16.187674)
			(size 0.4318 0.4318)
			(layers "F.Cu" "F.Mask" "F.Paste")
			(net "TP_CPU0_RSVD_42")
		)
		(pad "DH67" smd circle
			(at 20.938998 16.187674)
			(size 0.4318 0.4318)
			(layers "F.Cu" "F.Mask" "F.Paste")
			(net "GND")
		)
		(pad "DH69" smd circle
			(at 22.656038 16.187674)
			(size 0.4318 0.4318)
			(layers "F.Cu" "F.Mask" "F.Paste")
			(net "M_F_DQS_DP<11>")
		)
		(pad "DH71" smd circle
			(at 24.373078 16.187674)
			(size 0.4318 0.4318)
			(layers "F.Cu" "F.Mask" "F.Paste")
			(net "GND")
		)
		(pad "DH73" smd circle
			(at 26.090118 16.187674)
			(size 0.4318 0.4318)
			(layers "F.Cu" "F.Mask" "F.Paste")
			(net "GND")
		)
		(pad "DH75" smd circle
			(at 27.806904 16.187674)
			(size 0.4318 0.4318)
			(layers "F.Cu" "F.Mask" "F.Paste")
			(net "M_F_DQ<10>")
		)
		(pad "DH77" smd circle
			(at 29.523944 16.187674)
			(size 0.4318 0.4318)
			(layers "F.Cu" "F.Mask" "F.Paste")
			(net "M_F_DQ<15>")
		)
		(pad "DH79" smd circle
			(at 31.240984 16.187674)
			(size 0.4318 0.4318)
			(layers "F.Cu" "F.Mask" "F.Paste")
			(net "GND")
		)
		(pad "DH81" smd circle
			(at 32.958024 16.187674)
			(size 0.4318 0.4318)
			(layers "F.Cu" "F.Mask" "F.Paste")
			(net "GND")
		)
		(pad "DH83" smd circle
			(at 34.675064 16.187674)
			(size 0.4318 0.4318)
			(layers "F.Cu" "F.Mask" "F.Paste")
			(net "GND")
		)
		(pad "DH85" smd custom
			(at 36.392104 16.187674 270)
			(size 0.10795 0.10795)
			(layers "F.Cu" "F.Mask" "F.Paste")
			(net "M_D_DQ<9>")
			(options
				(clearance outline)
				(anchor circle)
			)
			(primitives
				(gr_poly
					(pts
						(arc
							(start 0.2159 -0.0381)
							(mid 0 -0.254)
							(end -0.2159 -0.0381)
						)
						(arc
							(start -0.2159 0.0381)
							(mid 0 0.254)
							(end 0.2159 0.0381)
						)
					)
					(width 0)
					(fill yes)
				)
			)
		)
		(pad "DJ2" smd custom
			(at -36.392104 18.483072 90)
			(size 0.10795 0.10795)
			(layers "F.Cu" "F.Mask" "F.Paste")
			(net "GND")
			(options
				(clearance outline)
				(anchor circle)
			)
			(primitives
				(gr_poly
					(pts
						(arc
							(start 0.2159 -0.0381)
							(mid 0 -0.254)
							(end -0.2159 -0.0381)
						)
						(arc
							(start -0.2159 0.0381)
							(mid 0 0.254)
							(end 0.2159 0.0381)
						)
					)
					(width 0)
					(fill yes)
				)
			)
		)
		(pad "DJ4" smd circle
			(at -34.675064 18.483072)
			(size 0.4318 0.4318)
			(layers "F.Cu" "F.Mask" "F.Paste")
			(net "P3E_CPU0_PE3_OCP_TXN<11>")
		)
		(pad "DJ6" smd circle
			(at -32.958024 18.483072)
			(size 0.4318 0.4318)
			(layers "F.Cu" "F.Mask" "F.Paste")
			(net "P3E_CPU0_PE3_OCP_TXN<12>")
		)
		(pad "DJ8" smd circle
			(at -31.240984 18.483072)
			(size 0.4318 0.4318)
			(layers "F.Cu" "F.Mask" "F.Paste")
			(net "P3E_CPU0_PE1_SS_RXP<6>")
		)
		(pad "DJ10" smd circle
			(at -29.523944 18.483072)
			(size 0.4318 0.4318)
			(layers "F.Cu" "F.Mask" "F.Paste")
			(net "GND")
		)
		(pad "DJ12" smd circle
			(at -27.806904 18.483072)
			(size 0.4318 0.4318)
			(layers "F.Cu" "F.Mask" "F.Paste")
			(net "P3E_CPU0_PE3_OCP_RXN<9>")
		)
		(pad "DJ14" smd circle
			(at -26.090118 18.483072)
			(size 0.4318 0.4318)
			(layers "F.Cu" "F.Mask" "F.Paste")
			(net "P3E_CPU0_PE3_OCP_RXP<7>")
		)
		(pad "DJ16" smd circle
			(at -24.373078 18.483072)
			(size 0.4318 0.4318)
			(layers "F.Cu" "F.Mask" "F.Paste")
			(net "PVCCIO_CPU0")
		)
		(pad "DJ18" smd circle
			(at -22.656038 18.483072)
			(size 0.4318 0.4318)
			(layers "F.Cu" "F.Mask" "F.Paste")
			(net "TP_CPU0_UPI2_RSVD_CG12")
		)
		(pad "DJ20" smd circle
			(at -20.938998 18.483072)
			(size 0.4318 0.4318)
			(layers "F.Cu" "F.Mask" "F.Paste")
			(net "TP_CPU0_UPI2_RSVD_CF11")
		)
		(pad "DJ22" smd circle
			(at -19.221958 18.483072)
			(size 0.4318 0.4318)
			(layers "F.Cu" "F.Mask" "F.Paste")
			(net "GND")
		)
		(pad "DJ24" smd circle
			(at -17.504918 18.483072)
			(size 0.4318 0.4318)
			(layers "F.Cu" "F.Mask" "F.Paste")
			(net "M_E_DQ<59>")
		)
		(pad "DJ26" smd circle
			(at -15.787878 18.483072)
			(size 0.4318 0.4318)
			(layers "F.Cu" "F.Mask" "F.Paste")
			(net "M_E_DQS_DP<7>")
		)
		(pad "DJ28" smd circle
			(at -14.071092 18.483072)
			(size 0.4318 0.4318)
			(layers "F.Cu" "F.Mask" "F.Paste")
			(net "M_E_DQ<61>")
		)
		(pad "DJ30" smd circle
			(at -12.354052 18.483072)
			(size 0.4318 0.4318)
			(layers "F.Cu" "F.Mask" "F.Paste")
			(net "M_F_DQ<43>")
		)
		(pad "DJ32" smd circle
			(at -10.637012 18.483072)
			(size 0.4318 0.4318)
			(layers "F.Cu" "F.Mask" "F.Paste")
			(net "M_F_DQS_DP<5>")
		)
		(pad "DJ34" smd circle
			(at -8.919972 18.483072)
			(size 0.4318 0.4318)
			(layers "F.Cu" "F.Mask" "F.Paste")
			(net "M_F_DQ<45>")
		)
		(pad "DJ36" smd circle
			(at -7.202932 18.483072)
			(size 0.4318 0.4318)
			(layers "F.Cu" "F.Mask" "F.Paste")
			(net "TP_CPU0_RSVD_41")
		)
		(pad "DJ38" smd circle
			(at -5.485892 18.483072)
			(size 0.4318 0.4318)
			(layers "F.Cu" "F.Mask" "F.Paste")
			(net "GND")
		)
		(pad "DJ40" smd circle
			(at -3.769106 18.483072)
			(size 0.4318 0.4318)
			(layers "F.Cu" "F.Mask" "F.Paste")
			(net "M_F_DQS_DP<4>")
		)
	)
)
